;LEADER: 12 
;HEADER: 
;CODE  : ASCII 
;FILE  : 9332_F0TG_MB_C_V02_0417_0820-bd-1-2.drl for backdrilling ... from layer TOP to layer GND
;DESIGN: 9332_F0TG_MB_C_V02_0417_0820.brd
;MUST-NOT-CUT-LAYER = IN1,  MAX_DRILL_DEPTH = 8.90 MILS,  MFG_STUB_LENGTH = 0.00 MILS
;   BackdrillSize 1. = 17.000000 Tolerance = +0.000000/-0.000000 NON_PLATED MILS Quantity = 32
%
G90
X0142576Y1640163
X0045812Y0451602
X0142576Y1643563
X0049212Y0451602
X0050880Y1418963
X0058349Y1409731
X0050880Y1415563
X0058349Y1406331
X0388630Y1236747
X0390974Y1219449
X0368726Y1214455
X0313284Y1215122
X0388630Y1240147
X0390974Y1222849
X0372126Y1214455
X0313284Y1218522
X1370685Y1223032
X1346063Y1214329
X1342036Y1203029
X1315657Y1196132
X1370685Y1226432
X1346063Y1217729
X1342036Y1206429
X1315657Y1199532
X0205479Y1648730
X0205479Y1652130
X0717398Y0960966
X1693540Y0960965
X0180067Y0960966
X1156209Y0960965
X0193679Y1640052
X0193679Y1643452
M30
